(kicad_pcb
	(version 20260206)
	(generator "pcbnew")
	(generator_version "10.0")
	(general
		(thickness 1.6)
		(legacy_teardrops no)
	)
	(paper "A4")
	(title_block
		(title "01162023_DA0F0TEBIF0_F0T_Expander_BD_F_brd_V02_OCP.brd")
		(comment 1 "Grand Teton / footprints 5459-5464 of 9728")
	)
	(layers
		(0 "F.Cu" signal "TOP")
		(4 "In1.Cu" signal "GND")
		(6 "In2.Cu" signal "VCC")
		(8 "In3.Cu" signal "VCC1")
		(10 "In4.Cu" signal "GND1")
		(12 "In5.Cu" signal "IN1")
		(14 "In6.Cu" signal "GND2")
		(16 "In7.Cu" signal "IN2")
		(18 "In8.Cu" signal "GND3")
		(20 "In9.Cu" signal "IN3")
		(22 "In10.Cu" signal "GND4")
		(24 "In11.Cu" signal "IN4")
		(26 "In12.Cu" signal "GND5")
		(28 "In13.Cu" signal "IN5")
		(30 "In14.Cu" signal "GND6")
		(32 "In15.Cu" signal "IN6")
		(34 "In16.Cu" signal "GND7")
		(2 "B.Cu" signal "BOTTOM")
		(9 "F.Adhes" user "F.Adhesive")
		(11 "B.Adhes" user "B.Adhesive")
		(13 "F.Paste" user "Package Geometry/Pastemask Top")
		(15 "B.Paste" user "Package Geometry/Pastemask Bottom")
		(5 "F.SilkS" user "Ref Des/Silkscreen Top")
		(7 "B.SilkS" user "Ref Des/Silkscreen Bottom")
		(1 "F.Mask" user "Board Geometry/Soldermask Top")
		(3 "B.Mask" user "Board Geometry/Soldermask Bottom")
		(17 "Dwgs.User" user "User.Drawings")
		(19 "Cmts.User" user "User.Comments")
		(21 "Eco1.User" user "User.Eco1")
		(23 "Eco2.User" user "User.Eco2")
		(25 "Edge.Cuts" user "Board Geometry/Outline")
		(27 "Margin" user)
		(31 "F.CrtYd" user "Package Geometry/Place Bound Top")
		(29 "B.CrtYd" user "Package Geometry/Place Bound Bottom")
		(35 "F.Fab" user "Ref Des/Assembly Top")
		(33 "B.Fab" user "Ref Des/Assembly Bottom")
	)
	(footprint ""
		(layer "F.Cu")
		(at 89.002108 -306.074572 90)
		(property "Reference" "R1236"
			(at 0 0 90)
			(layer "F.SilkS")
			(hide yes)
			(effects
				(font
					(size 1.27 1.27)
				)
			)
		)
		(property "Value" ""
			(at 0 0 90)
			(layer "F.Fab")
			(effects
				(font
					(size 1.27 1.27)
				)
			)
		)
		(duplicate_pad_numbers_are_jumpers no)
		(fp_line
			(start 0.7874 -0.4064)
			(end 0.7874 0.4064)
			(stroke
				(width 0.1524)
				(type default)
			)
			(layer "F.SilkS")
		)
		(fp_line
			(start -0.7874 -0.4064)
			(end 0.7874 -0.4064)
			(stroke
				(width 0.1524)
				(type default)
			)
			(layer "F.SilkS")
		)
		(fp_line
			(start 0.7874 0.4064)
			(end -0.7874 0.4064)
			(stroke
				(width 0.1524)
				(type default)
			)
			(layer "F.SilkS")
		)
		(fp_line
			(start -0.7874 0.4064)
			(end -0.7874 -0.4064)
			(stroke
				(width 0.1524)
				(type default)
			)
			(layer "F.SilkS")
		)
		(fp_line
			(start -0.12065 -0.305054)
			(end -0.12065 -0.2794)
			(stroke
				(width 0.1)
				(type default)
			)
			(layer "F.Fab")
		)
		(fp_line
			(start -0.67945 -0.305054)
			(end -0.12065 -0.305054)
			(stroke
				(width 0.1)
				(type default)
			)
			(layer "F.Fab")
		)
		(fp_line
			(start 0.67945 -0.3048)
			(end 0.67945 0.3048)
			(stroke
				(width 0.1)
				(type default)
			)
			(layer "F.Fab")
		)
		(fp_line
			(start 0.12065 -0.3048)
			(end 0.67945 -0.3048)
			(stroke
				(width 0.1)
				(type default)
			)
			(layer "F.Fab")
		)
		(fp_line
			(start 0.12065 -0.2794)
			(end 0.12065 -0.3048)
			(stroke
				(width 0.1)
				(type default)
			)
			(layer "F.Fab")
		)
		(fp_line
			(start -0.12065 -0.2794)
			(end 0.12065 -0.2794)
			(stroke
				(width 0.1)
				(type default)
			)
			(layer "F.Fab")
		)
		(fp_line
			(start 0.120396 0.2794)
			(end -0.12065 0.2794)
			(stroke
				(width 0.1)
				(type default)
			)
			(layer "F.Fab")
		)
		(fp_line
			(start -0.12065 0.2794)
			(end -0.12065 0.3048)
			(stroke
				(width 0.1)
				(type default)
			)
			(layer "F.Fab")
		)
		(fp_line
			(start 0.67945 0.3048)
			(end 0.120396 0.3048)
			(stroke
				(width 0.1)
				(type default)
			)
			(layer "F.Fab")
		)
		(fp_line
			(start 0.120396 0.3048)
			(end 0.120396 0.2794)
			(stroke
				(width 0.1)
				(type default)
			)
			(layer "F.Fab")
		)
		(fp_line
			(start -0.12065 0.3048)
			(end -0.67945 0.3048)
			(stroke
				(width 0.1)
				(type default)
			)
			(layer "F.Fab")
		)
		(fp_line
			(start -0.67945 0.3048)
			(end -0.67945 -0.305054)
			(stroke
				(width 0.1)
				(type default)
			)
			(layer "F.Fab")
		)
		(pad "1" smd circle
			(at -0.40005 0 90)
			(size 0 0)
			(layers "F.Cu" "F.Mask" "F.Paste")
			(net "PEX0_SPARE4")
		)
		(pad "2" smd circle
			(at 0.40005 0 90)
			(size 0 0)
			(layers "F.Cu" "F.Mask" "F.Paste")
			(net "P1V8_PEX")
		)
	)
	(footprint ""
		(layer "F.Cu")
		(at 259.190998 -255.359662)
		(property "Reference" "C3413"
			(at 0 0 0)
			(layer "F.SilkS")
			(hide yes)
			(effects
				(font
					(size 1.27 1.27)
				)
			)
		)
		(property "Value" ""
			(at 0 0 0)
			(layer "F.Fab")
			(effects
				(font
					(size 1.27 1.27)
				)
			)
		)
		(duplicate_pad_numbers_are_jumpers no)
		(fp_line
			(start -1.2954 -0.5842)
			(end 1.2954 -0.5842)
			(stroke
				(width 0.1524)
				(type default)
			)
			(layer "F.SilkS")
		)
		(fp_line
			(start -1.2954 0.5842)
			(end -1.2954 -0.5842)
			(stroke
				(width 0.1524)
				(type default)
			)
			(layer "F.SilkS")
		)
		(fp_line
			(start 1.2954 -0.5842)
			(end 1.2954 0.5842)
			(stroke
				(width 0.1524)
				(type default)
			)
			(layer "F.SilkS")
		)
		(fp_line
			(start 1.2954 0.5842)
			(end -1.2954 0.5842)
			(stroke
				(width 0.1524)
				(type default)
			)
			(layer "F.SilkS")
		)
		(fp_line
			(start -1.1938 -0.4064)
			(end -0.8636 -0.4064)
			(stroke
				(width 0.1)
				(type default)
			)
			(layer "F.Fab")
		)
		(fp_line
			(start -1.1938 0.4064)
			(end -1.1938 -0.4064)
			(stroke
				(width 0.1)
				(type default)
			)
			(layer "F.Fab")
		)
		(fp_line
			(start -0.8636 -0.4572)
			(end 0.8636 -0.4572)
			(stroke
				(width 0.1)
				(type default)
			)
			(layer "F.Fab")
		)
		(fp_line
			(start -0.8636 -0.4064)
			(end -0.8636 -0.4572)
			(stroke
				(width 0.1)
				(type default)
			)
			(layer "F.Fab")
		)
		(fp_line
			(start -0.8636 0.4064)
			(end -1.1938 0.4064)
			(stroke
				(width 0.1)
				(type default)
			)
			(layer "F.Fab")
		)
		(fp_line
			(start -0.8636 0.4572)
			(end -0.8636 0.4064)
			(stroke
				(width 0.1)
				(type default)
			)
			(layer "F.Fab")
		)
		(fp_line
			(start 0.8636 -0.4572)
			(end 0.8636 -0.4064)
			(stroke
				(width 0.1)
				(type default)
			)
			(layer "F.Fab")
		)
		(fp_line
			(start 0.8636 -0.4064)
			(end 1.1938 -0.4064)
			(stroke
				(width 0.1)
				(type default)
			)
			(layer "F.Fab")
		)
		(fp_line
			(start 0.8636 0.4064)
			(end 0.8636 0.4572)
			(stroke
				(width 0.1)
				(type default)
			)
			(layer "F.Fab")
		)
		(fp_line
			(start 0.8636 0.4572)
			(end -0.8636 0.4572)
			(stroke
				(width 0.1)
				(type default)
			)
			(layer "F.Fab")
		)
		(fp_line
			(start 1.1938 -0.4064)
			(end 1.1938 0.4064)
			(stroke
				(width 0.1)
				(type default)
			)
			(layer "F.Fab")
		)
		(fp_line
			(start 1.1938 0.4064)
			(end 0.8636 0.4064)
			(stroke
				(width 0.1)
				(type default)
			)
			(layer "F.Fab")
		)
		(pad "1" smd rect
			(at -0.7366 0 270)
			(size 0.7112 0.8128)
			(layers "F.Cu" "F.Mask" "F.Paste")
			(net "P1V8_PLL0_PEX2")
		)
		(pad "2" smd rect
			(at 0.7366 0 270)
			(size 0.7112 0.8128)
			(layers "F.Cu" "F.Mask" "F.Paste")
			(net "GND")
		)
	)
	(footprint ""
		(layer "F.Cu")
		(at 166.330884 -193.836798)
		(property "Reference" "R3409"
			(at 0 0 0)
			(layer "F.SilkS")
			(hide yes)
			(effects
				(font
					(size 1.27 1.27)
				)
			)
		)
		(property "Value" ""
			(at 0 0 0)
			(layer "F.Fab")
			(effects
				(font
					(size 1.27 1.27)
				)
			)
		)
		(duplicate_pad_numbers_are_jumpers no)
		(fp_line
			(start -0.7874 -0.4064)
			(end 0.7874 -0.4064)
			(stroke
				(width 0.1524)
				(type default)
			)
			(layer "F.SilkS")
		)
		(fp_line
			(start -0.7874 0.4064)
			(end -0.7874 -0.4064)
			(stroke
				(width 0.1524)
				(type default)
			)
			(layer "F.SilkS")
		)
		(fp_line
			(start 0.7874 -0.4064)
			(end 0.7874 0.4064)
			(stroke
				(width 0.1524)
				(type default)
			)
			(layer "F.SilkS")
		)
		(fp_line
			(start 0.7874 0.4064)
			(end -0.7874 0.4064)
			(stroke
				(width 0.1524)
				(type default)
			)
			(layer "F.SilkS")
		)
		(fp_line
			(start -0.67945 -0.305054)
			(end -0.12065 -0.305054)
			(stroke
				(width 0.1)
				(type default)
			)
			(layer "F.Fab")
		)
		(fp_line
			(start -0.67945 0.3048)
			(end -0.67945 -0.305054)
			(stroke
				(width 0.1)
				(type default)
			)
			(layer "F.Fab")
		)
		(fp_line
			(start -0.12065 -0.305054)
			(end -0.12065 -0.2794)
			(stroke
				(width 0.1)
				(type default)
			)
			(layer "F.Fab")
		)
		(fp_line
			(start -0.12065 -0.2794)
			(end 0.12065 -0.2794)
			(stroke
				(width 0.1)
				(type default)
			)
			(layer "F.Fab")
		)
		(fp_line
			(start -0.12065 0.2794)
			(end -0.12065 0.3048)
			(stroke
				(width 0.1)
				(type default)
			)
			(layer "F.Fab")
		)
		(fp_line
			(start -0.12065 0.3048)
			(end -0.67945 0.3048)
			(stroke
				(width 0.1)
				(type default)
			)
			(layer "F.Fab")
		)
		(fp_line
			(start 0.120396 0.2794)
			(end -0.12065 0.2794)
			(stroke
				(width 0.1)
				(type default)
			)
			(layer "F.Fab")
		)
		(fp_line
			(start 0.120396 0.3048)
			(end 0.120396 0.2794)
			(stroke
				(width 0.1)
				(type default)
			)
			(layer "F.Fab")
		)
		(fp_line
			(start 0.12065 -0.3048)
			(end 0.67945 -0.3048)
			(stroke
				(width 0.1)
				(type default)
			)
			(layer "F.Fab")
		)
		(fp_line
			(start 0.12065 -0.2794)
			(end 0.12065 -0.3048)
			(stroke
				(width 0.1)
				(type default)
			)
			(layer "F.Fab")
		)
		(fp_line
			(start 0.67945 -0.3048)
			(end 0.67945 0.3048)
			(stroke
				(width 0.1)
				(type default)
			)
			(layer "F.Fab")
		)
		(fp_line
			(start 0.67945 0.3048)
			(end 0.120396 0.3048)
			(stroke
				(width 0.1)
				(type default)
			)
			(layer "F.Fab")
		)
		(pad "1" smd circle
			(at -0.40005 0)
			(size 0 0)
			(layers "F.Cu" "F.Mask" "F.Paste")
			(net "SPI_BIC1_MISO_LS01_R2")
		)
		(pad "2" smd circle
			(at 0.40005 0)
			(size 0 0)
			(layers "F.Cu" "F.Mask" "F.Paste")
			(net "SPI_BIC1_MISO_LS01_R")
		)
	)
	(footprint ""
		(layer "F.Cu")
		(at 370.563648 -146.592798 -90)
		(property "Reference" "R755"
			(at 0 0 270)
			(layer "F.SilkS")
			(hide yes)
			(effects
				(font
					(size 1.27 1.27)
				)
			)
		)
		(property "Value" ""
			(at 0 0 270)
			(layer "F.Fab")
			(effects
				(font
					(size 1.27 1.27)
				)
			)
		)
		(duplicate_pad_numbers_are_jumpers no)
		(fp_line
			(start -0.7874 0.4064)
			(end -0.7874 -0.4064)
			(stroke
				(width 0.1524)
				(type default)
			)
			(layer "F.SilkS")
		)
		(fp_line
			(start 0.7874 0.4064)
			(end -0.7874 0.4064)
			(stroke
				(width 0.1524)
				(type default)
			)
			(layer "F.SilkS")
		)
		(fp_line
			(start -0.7874 -0.4064)
			(end 0.7874 -0.4064)
			(stroke
				(width 0.1524)
				(type default)
			)
			(layer "F.SilkS")
		)
		(fp_line
			(start 0.7874 -0.4064)
			(end 0.7874 0.4064)
			(stroke
				(width 0.1524)
				(type default)
			)
			(layer "F.SilkS")
		)
		(fp_line
			(start -0.67945 0.3048)
			(end -0.67945 -0.305054)
			(stroke
				(width 0.1)
				(type default)
			)
			(layer "F.Fab")
		)
		(fp_line
			(start -0.12065 0.3048)
			(end -0.67945 0.3048)
			(stroke
				(width 0.1)
				(type default)
			)
			(layer "F.Fab")
		)
		(fp_line
			(start 0.120396 0.3048)
			(end 0.120396 0.2794)
			(stroke
				(width 0.1)
				(type default)
			)
			(layer "F.Fab")
		)
		(fp_line
			(start 0.67945 0.3048)
			(end 0.120396 0.3048)
			(stroke
				(width 0.1)
				(type default)
			)
			(layer "F.Fab")
		)
		(fp_line
			(start -0.12065 0.2794)
			(end -0.12065 0.3048)
			(stroke
				(width 0.1)
				(type default)
			)
			(layer "F.Fab")
		)
		(fp_line
			(start 0.120396 0.2794)
			(end -0.12065 0.2794)
			(stroke
				(width 0.1)
				(type default)
			)
			(layer "F.Fab")
		)
		(fp_line
			(start -0.12065 -0.2794)
			(end 0.12065 -0.2794)
			(stroke
				(width 0.1)
				(type default)
			)
			(layer "F.Fab")
		)
		(fp_line
			(start 0.12065 -0.2794)
			(end 0.12065 -0.3048)
			(stroke
				(width 0.1)
				(type default)
			)
			(layer "F.Fab")
		)
		(fp_line
			(start 0.12065 -0.3048)
			(end 0.67945 -0.3048)
			(stroke
				(width 0.1)
				(type default)
			)
			(layer "F.Fab")
		)
		(fp_line
			(start 0.67945 -0.3048)
			(end 0.67945 0.3048)
			(stroke
				(width 0.1)
				(type default)
			)
			(layer "F.Fab")
		)
		(fp_line
			(start -0.67945 -0.305054)
			(end -0.12065 -0.305054)
			(stroke
				(width 0.1)
				(type default)
			)
			(layer "F.Fab")
		)
		(fp_line
			(start -0.12065 -0.305054)
			(end -0.12065 -0.2794)
			(stroke
				(width 0.1)
				(type default)
			)
			(layer "F.Fab")
		)
		(pad "1" smd circle
			(at -0.40005 0 270)
			(size 0 0)
			(layers "F.Cu" "F.Mask" "F.Paste")
			(net "P12V_NIC6_R")
		)
		(pad "2" smd circle
			(at 0.40005 0 270)
			(size 0 0)
			(layers "F.Cu" "F.Mask" "F.Paste")
			(net "P12V_NIC6_VIN_P")
		)
	)
	(footprint ""
		(layer "F.Cu")
		(at 265.240008 -256.634234 180)
		(property "Reference" "C3398"
			(at 0 0 180)
			(layer "F.SilkS")
			(hide yes)
			(effects
				(font
					(size 1.27 1.27)
				)
			)
		)
		(property "Value" ""
			(at 0 0 180)
			(layer "F.Fab")
			(effects
				(font
					(size 1.27 1.27)
				)
			)
		)
		(duplicate_pad_numbers_are_jumpers no)
		(fp_line
			(start 1.2954 0.5842)
			(end -1.2954 0.5842)
			(stroke
				(width 0.1524)
				(type default)
			)
			(layer "F.SilkS")
		)
		(fp_line
			(start 1.2954 -0.5842)
			(end 1.2954 0.5842)
			(stroke
				(width 0.1524)
				(type default)
			)
			(layer "F.SilkS")
		)
		(fp_line
			(start -1.2954 0.5842)
			(end -1.2954 -0.5842)
			(stroke
				(width 0.1524)
				(type default)
			)
			(layer "F.SilkS")
		)
		(fp_line
			(start -1.2954 -0.5842)
			(end 1.2954 -0.5842)
			(stroke
				(width 0.1524)
				(type default)
			)
			(layer "F.SilkS")
		)
		(fp_line
			(start 1.1938 0.4064)
			(end 0.8636 0.4064)
			(stroke
				(width 0.1)
				(type default)
			)
			(layer "F.Fab")
		)
		(fp_line
			(start 1.1938 -0.4064)
			(end 1.1938 0.4064)
			(stroke
				(width 0.1)
				(type default)
			)
			(layer "F.Fab")
		)
		(fp_line
			(start 0.8636 0.4572)
			(end -0.8636 0.4572)
			(stroke
				(width 0.1)
				(type default)
			)
			(layer "F.Fab")
		)
		(fp_line
			(start 0.8636 0.4064)
			(end 0.8636 0.4572)
			(stroke
				(width 0.1)
				(type default)
			)
			(layer "F.Fab")
		)
		(fp_line
			(start 0.8636 -0.4064)
			(end 1.1938 -0.4064)
			(stroke
				(width 0.1)
				(type default)
			)
			(layer "F.Fab")
		)
		(fp_line
			(start 0.8636 -0.4572)
			(end 0.8636 -0.4064)
			(stroke
				(width 0.1)
				(type default)
			)
			(layer "F.Fab")
		)
		(fp_line
			(start -0.8636 0.4572)
			(end -0.8636 0.4064)
			(stroke
				(width 0.1)
				(type default)
			)
			(layer "F.Fab")
		)
		(fp_line
			(start -0.8636 0.4064)
			(end -1.1938 0.4064)
			(stroke
				(width 0.1)
				(type default)
			)
			(layer "F.Fab")
		)
		(fp_line
			(start -0.8636 -0.4064)
			(end -0.8636 -0.4572)
			(stroke
				(width 0.1)
				(type default)
			)
			(layer "F.Fab")
		)
		(fp_line
			(start -0.8636 -0.4572)
			(end 0.8636 -0.4572)
			(stroke
				(width 0.1)
				(type default)
			)
			(layer "F.Fab")
		)
		(fp_line
			(start -1.1938 0.4064)
			(end -1.1938 -0.4064)
			(stroke
				(width 0.1)
				(type default)
			)
			(layer "F.Fab")
		)
		(fp_line
			(start -1.1938 -0.4064)
			(end -0.8636 -0.4064)
			(stroke
				(width 0.1)
				(type default)
			)
			(layer "F.Fab")
		)
		(pad "1" smd rect
			(at -0.7366 0 90)
			(size 0.7112 0.8128)
			(layers "F.Cu" "F.Mask" "F.Paste")
			(net "PCEPLL5_VDDA18_PEX2_R")
		)
		(pad "2" smd rect
			(at 0.7366 0 90)
			(size 0.7112 0.8128)
			(layers "F.Cu" "F.Mask" "F.Paste")
			(net "GND")
		)
	)
	(footprint ""
		(layer "F.Cu")
		(at 152.411938 -137.2489 -90)
		(property "Reference" "C889"
			(at 0 0 270)
			(layer "F.SilkS")
			(hide yes)
			(effects
				(font
					(size 1.27 1.27)
				)
			)
		)
		(property "Value" ""
			(at 0 0 270)
			(layer "F.Fab")
			(effects
				(font
					(size 1.27 1.27)
				)
			)
		)
		(duplicate_pad_numbers_are_jumpers no)
		(fp_line
			(start -0.7874 0.4064)
			(end -0.7874 -0.4064)
			(stroke
				(width 0.1524)
				(type default)
			)
			(layer "F.SilkS")
		)
		(fp_line
			(start 0.7874 0.4064)
			(end -0.7874 0.4064)
			(stroke
				(width 0.1524)
				(type default)
			)
			(layer "F.SilkS")
		)
		(fp_line
			(start -0.7874 -0.4064)
			(end 0.7874 -0.4064)
			(stroke
				(width 0.1524)
				(type default)
			)
			(layer "F.SilkS")
		)
		(fp_line
			(start 0.7874 -0.4064)
			(end 0.7874 0.4064)
			(stroke
				(width 0.1524)
				(type default)
			)
			(layer "F.SilkS")
		)
		(fp_line
			(start -0.67945 0.3048)
			(end -0.67945 -0.305054)
			(stroke
				(width 0.1)
				(type default)
			)
			(layer "F.Fab")
		)
		(fp_line
			(start -0.12065 0.3048)
			(end -0.67945 0.3048)
			(stroke
				(width 0.1)
				(type default)
			)
			(layer "F.Fab")
		)
		(fp_line
			(start 0.120396 0.3048)
			(end 0.120396 0.2794)
			(stroke
				(width 0.1)
				(type default)
			)
			(layer "F.Fab")
		)
		(fp_line
			(start 0.67945 0.3048)
			(end 0.120396 0.3048)
			(stroke
				(width 0.1)
				(type default)
			)
			(layer "F.Fab")
		)
		(fp_line
			(start -0.12065 0.2794)
			(end -0.12065 0.3048)
			(stroke
				(width 0.1)
				(type default)
			)
			(layer "F.Fab")
		)
		(fp_line
			(start 0.120396 0.2794)
			(end -0.12065 0.2794)
			(stroke
				(width 0.1)
				(type default)
			)
			(layer "F.Fab")
		)
		(fp_line
			(start -0.12065 -0.2794)
			(end 0.12065 -0.2794)
			(stroke
				(width 0.1)
				(type default)
			)
			(layer "F.Fab")
		)
		(fp_line
			(start 0.12065 -0.2794)
			(end 0.12065 -0.3048)
			(stroke
				(width 0.1)
				(type default)
			)
			(layer "F.Fab")
		)
		(fp_line
			(start 0.12065 -0.3048)
			(end 0.67945 -0.3048)
			(stroke
				(width 0.1)
				(type default)
			)
			(layer "F.Fab")
		)
		(fp_line
			(start 0.67945 -0.3048)
			(end 0.67945 0.3048)
			(stroke
				(width 0.1)
				(type default)
			)
			(layer "F.Fab")
		)
		(fp_line
			(start -0.67945 -0.305054)
			(end -0.12065 -0.305054)
			(stroke
				(width 0.1)
				(type default)
			)
			(layer "F.Fab")
		)
		(fp_line
			(start -0.12065 -0.305054)
			(end -0.12065 -0.2794)
			(stroke
				(width 0.1)
				(type default)
			)
			(layer "F.Fab")
		)
		(pad "1" smd circle
			(at -0.40005 0 270)
			(size 0 0)
			(layers "F.Cu" "F.Mask" "F.Paste")
			(net "P3V3_NIC2")
		)
		(pad "2" smd circle
			(at 0.40005 0 270)
			(size 0 0)
			(layers "F.Cu" "F.Mask" "F.Paste")
			(net "GND")
		)
	)
)
